(kicad_pcb
	(version 20260206)
	(generator "pcbnew")
	(generator_version "10.0")
	(general
		(thickness 1.6)
		(legacy_teardrops no)
	)
	(paper "A4")
	(title_block
		(title "04192023_DAF0TMB3IC0_F0TG_MB_C_brd_V02_OCP.brd")
		(comment 1 "Grand Teton / footprints 191-197 of 8354")
	)
	(layers
		(0 "F.Cu" signal "TOP")
		(4 "In1.Cu" signal "GND")
		(6 "In2.Cu" signal "IN1")
		(8 "In3.Cu" signal "GND1")
		(10 "In4.Cu" signal "IN2")
		(12 "In5.Cu" signal "GND2")
		(14 "In6.Cu" signal "IN3")
		(16 "In7.Cu" signal "GND3")
		(18 "In8.Cu" signal "VCC")
		(20 "In9.Cu" signal "VCC1")
		(22 "In10.Cu" signal "GND4")
		(24 "In11.Cu" signal "IN4")
		(26 "In12.Cu" signal "GND5")
		(28 "In13.Cu" signal "IN5")
		(30 "In14.Cu" signal "GND6")
		(32 "In15.Cu" signal "IN6")
		(34 "In16.Cu" signal "GND7")
		(2 "B.Cu" signal "BOTTOM")
		(9 "F.Adhes" user "F.Adhesive")
		(11 "B.Adhes" user "B.Adhesive")
		(13 "F.Paste" user "Package Geometry/Pastemask Top")
		(15 "B.Paste" user "Package Geometry/Pastemask Bottom")
		(5 "F.SilkS" user "Ref Des/Silkscreen Top")
		(7 "B.SilkS" user "Ref Des/Silkscreen Bottom")
		(1 "F.Mask" user "Board Geometry/Soldermask Top")
		(3 "B.Mask" user "Board Geometry/Soldermask Bottom")
		(17 "Dwgs.User" user "User.Drawings")
		(19 "Cmts.User" user "User.Comments")
		(21 "Eco1.User" user "User.Eco1")
		(23 "Eco2.User" user "User.Eco2")
		(25 "Edge.Cuts" user "Board Geometry/Outline")
		(27 "Margin" user)
		(31 "F.CrtYd" user "Package Geometry/Place Bound Top")
		(29 "B.CrtYd" user "Package Geometry/Place Bound Bottom")
		(35 "F.Fab" user "Ref Des/Assembly Top")
		(33 "B.Fab" user "Ref Des/Assembly Bottom")
	)
	(footprint ""
		(layer "F.Cu")
		(at 127.705104 -53.15839 180)
		(property "Reference" "C86"
			(at 0 0 180)
			(layer "F.SilkS")
			(hide yes)
			(effects
				(font
					(size 1.27 1.27)
				)
			)
		)
		(property "Value" ""
			(at 0 0 180)
			(layer "F.Fab")
			(effects
				(font
					(size 1.27 1.27)
				)
			)
		)
		(duplicate_pad_numbers_are_jumpers no)
		(fp_line
			(start 0.7874 0.4064)
			(end -0.7874 0.4064)
			(stroke
				(width 0.1524)
				(type default)
			)
			(layer "F.SilkS")
		)
		(fp_line
			(start 0.7874 -0.4064)
			(end 0.7874 0.4064)
			(stroke
				(width 0.1524)
				(type default)
			)
			(layer "F.SilkS")
		)
		(fp_line
			(start -0.7874 0.4064)
			(end -0.7874 -0.4064)
			(stroke
				(width 0.1524)
				(type default)
			)
			(layer "F.SilkS")
		)
		(fp_line
			(start -0.7874 -0.4064)
			(end 0.7874 -0.4064)
			(stroke
				(width 0.1524)
				(type default)
			)
			(layer "F.SilkS")
		)
		(fp_line
			(start 0.67945 0.3048)
			(end 0.120396 0.3048)
			(stroke
				(width 0.1)
				(type default)
			)
			(layer "F.Fab")
		)
		(fp_line
			(start 0.67945 -0.3048)
			(end 0.67945 0.3048)
			(stroke
				(width 0.1)
				(type default)
			)
			(layer "F.Fab")
		)
		(fp_line
			(start 0.12065 -0.2794)
			(end 0.12065 -0.3048)
			(stroke
				(width 0.1)
				(type default)
			)
			(layer "F.Fab")
		)
		(fp_line
			(start 0.12065 -0.3048)
			(end 0.67945 -0.3048)
			(stroke
				(width 0.1)
				(type default)
			)
			(layer "F.Fab")
		)
		(fp_line
			(start 0.120396 0.3048)
			(end 0.120396 0.2794)
			(stroke
				(width 0.1)
				(type default)
			)
			(layer "F.Fab")
		)
		(fp_line
			(start 0.120396 0.2794)
			(end -0.12065 0.2794)
			(stroke
				(width 0.1)
				(type default)
			)
			(layer "F.Fab")
		)
		(fp_line
			(start -0.12065 0.3048)
			(end -0.67945 0.3048)
			(stroke
				(width 0.1)
				(type default)
			)
			(layer "F.Fab")
		)
		(fp_line
			(start -0.12065 0.2794)
			(end -0.12065 0.3048)
			(stroke
				(width 0.1)
				(type default)
			)
			(layer "F.Fab")
		)
		(fp_line
			(start -0.12065 -0.2794)
			(end 0.12065 -0.2794)
			(stroke
				(width 0.1)
				(type default)
			)
			(layer "F.Fab")
		)
		(fp_line
			(start -0.12065 -0.305054)
			(end -0.12065 -0.2794)
			(stroke
				(width 0.1)
				(type default)
			)
			(layer "F.Fab")
		)
		(fp_line
			(start -0.67945 0.3048)
			(end -0.67945 -0.305054)
			(stroke
				(width 0.1)
				(type default)
			)
			(layer "F.Fab")
		)
		(fp_line
			(start -0.67945 -0.305054)
			(end -0.12065 -0.305054)
			(stroke
				(width 0.1)
				(type default)
			)
			(layer "F.Fab")
		)
		(pad "1" smd circle
			(at -0.40005 0 180)
			(size 0 0)
			(layers "F.Cu" "F.Mask" "F.Paste")
			(net "JTAG_TDI")
		)
		(pad "2" smd circle
			(at 0.40005 0 180)
			(size 0 0)
			(layers "F.Cu" "F.Mask" "F.Paste")
			(net "GND")
		)
	)
	(footprint ""
		(layer "F.Cu")
		(at 259.461 -385.27736 90)
		(property "Reference" "PPQ6"
			(at -7.487412 -2.39268 0)
			(unlocked yes)
			(layer "F.SilkS")
			(effects
				(font
					(size 0.7874 0.5842)
					(thickness 0.1524)
				)
				(justify left)
			)
		)
		(property "Value" ""
			(at 0 0 90)
			(layer "F.Fab")
			(effects
				(font
					(size 1.27 1.27)
				)
			)
		)
		(duplicate_pad_numbers_are_jumpers no)
		(fp_line
			(start 2.350008 -2.649982)
			(end 2.350008 -2.4892)
			(stroke
				(width 0.1524)
				(type default)
			)
			(layer "F.SilkS")
		)
		(fp_line
			(start -2.350008 -2.649982)
			(end 2.350008 -2.649982)
			(stroke
				(width 0.1524)
				(type default)
			)
			(layer "F.SilkS")
		)
		(fp_line
			(start -2.350008 -2.4384)
			(end -2.350008 -2.649982)
			(stroke
				(width 0.1524)
				(type default)
			)
			(layer "F.SilkS")
		)
		(fp_line
			(start 2.350008 2.4892)
			(end 2.350008 2.649982)
			(stroke
				(width 0.1524)
				(type default)
			)
			(layer "F.SilkS")
		)
		(fp_line
			(start 2.350008 2.649982)
			(end -2.350008 2.649982)
			(stroke
				(width 0.1524)
				(type default)
			)
			(layer "F.SilkS")
		)
		(fp_line
			(start -2.350008 2.649982)
			(end -2.350008 2.413)
			(stroke
				(width 0.1524)
				(type default)
			)
			(layer "F.SilkS")
		)
		(fp_poly
			(pts
				(xy -3.506216 -3.488944) (xy -2.706116 -3.488944) (xy -3.125216 -2.447544)
			)
			(stroke
				(width 0)
				(type default)
			)
			(fill yes)
			(layer "F.SilkS")
		)
		(fp_line
			(start 2.350008 -2.649982)
			(end 2.350008 2.649982)
			(stroke
				(width 0.1)
				(type default)
			)
			(layer "F.Fab")
		)
		(fp_line
			(start -2.350008 -2.649982)
			(end 2.350008 -2.649982)
			(stroke
				(width 0.1)
				(type default)
			)
			(layer "F.Fab")
		)
		(fp_line
			(start 2.350008 2.649982)
			(end -2.350008 2.649982)
			(stroke
				(width 0.1)
				(type default)
			)
			(layer "F.Fab")
		)
		(fp_line
			(start -2.350008 2.649982)
			(end -2.350008 -2.649982)
			(stroke
				(width 0.1)
				(type default)
			)
			(layer "F.Fab")
		)
		(fp_poly
			(pts
				(xy -3.717544 -1.905) (xy -4.758944 -2.3241) (xy -4.758944 -1.524)
			)
			(stroke
				(width 0)
				(type default)
			)
			(fill yes)
			(layer "F.Fab")
		)
		(pad "1" smd rect
			(at -2.999994 -1.905)
			(size 0.7112 1.1684)
			(layers "F.Cu" "F.Mask" "F.Paste")
			(net "P12V_AUX")
		)
		(pad "2" smd rect
			(at -2.999994 -0.635)
			(size 0.7112 1.1684)
			(layers "F.Cu" "F.Mask" "F.Paste")
			(net "P12V_AUX")
		)
		(pad "3" smd rect
			(at -2.999994 0.635)
			(size 0.7112 1.1684)
			(layers "F.Cu" "F.Mask" "F.Paste")
			(net "P12V_AUX")
		)
		(pad "4" smd rect
			(at -2.999994 1.905)
			(size 0.7112 1.1684)
			(layers "F.Cu" "F.Mask" "F.Paste")
			(net "P12V_HSC_GATE_G2")
		)
		(pad "5" smd circle
			(at 0.925068 0)
			(size 0 0)
			(layers "F.Cu" "F.Mask" "F.Paste")
			(net "P12V_MAIN_R")
		)
		(zone
			(layer "F.Cu")
			(hatch none 0.5)
			(connect_pads
				(clearance 0)
			)
			(min_thickness 0.25)
			(keepout
				(tracks not_allowed)
				(vias allowed)
				(pads allowed)
				(copperpour not_allowed)
				(footprints allowed)
			)
			(placement
				(enabled no)
				(sheetname "")
			)
			(fill
				(thermal_gap 0.5)
				(thermal_bridge_width 0.5)
				(island_removal_mode 0)
			)
			(polygon
				(pts
					(xy 256.8194 -383.7178) (xy 262.1026 -383.7178) (xy 262.1026 -382.92786) (xy 256.8194 -382.92786)
				)
			)
		)
	)
	(footprint ""
		(layer "F.Cu")
		(at 85.81771 -340.190074)
		(property "Reference" "PR255"
			(at 0 0 0)
			(layer "F.SilkS")
			(hide yes)
			(effects
				(font
					(size 1.27 1.27)
				)
			)
		)
		(property "Value" ""
			(at 0 0 0)
			(layer "F.Fab")
			(effects
				(font
					(size 1.27 1.27)
				)
			)
		)
		(duplicate_pad_numbers_are_jumpers no)
		(fp_line
			(start -0.7874 -0.4064)
			(end 0.7874 -0.4064)
			(stroke
				(width 0.1524)
				(type default)
			)
			(layer "F.SilkS")
		)
		(fp_line
			(start -0.7874 0.4064)
			(end -0.7874 -0.4064)
			(stroke
				(width 0.1524)
				(type default)
			)
			(layer "F.SilkS")
		)
		(fp_line
			(start 0.7874 -0.4064)
			(end 0.7874 0.4064)
			(stroke
				(width 0.1524)
				(type default)
			)
			(layer "F.SilkS")
		)
		(fp_line
			(start 0.7874 0.4064)
			(end -0.7874 0.4064)
			(stroke
				(width 0.1524)
				(type default)
			)
			(layer "F.SilkS")
		)
		(fp_line
			(start -0.67945 -0.305054)
			(end -0.12065 -0.305054)
			(stroke
				(width 0.1)
				(type default)
			)
			(layer "F.Fab")
		)
		(fp_line
			(start -0.67945 0.3048)
			(end -0.67945 -0.305054)
			(stroke
				(width 0.1)
				(type default)
			)
			(layer "F.Fab")
		)
		(fp_line
			(start -0.12065 -0.305054)
			(end -0.12065 -0.2794)
			(stroke
				(width 0.1)
				(type default)
			)
			(layer "F.Fab")
		)
		(fp_line
			(start -0.12065 -0.2794)
			(end 0.12065 -0.2794)
			(stroke
				(width 0.1)
				(type default)
			)
			(layer "F.Fab")
		)
		(fp_line
			(start -0.12065 0.2794)
			(end -0.12065 0.3048)
			(stroke
				(width 0.1)
				(type default)
			)
			(layer "F.Fab")
		)
		(fp_line
			(start -0.12065 0.3048)
			(end -0.67945 0.3048)
			(stroke
				(width 0.1)
				(type default)
			)
			(layer "F.Fab")
		)
		(fp_line
			(start 0.120396 0.2794)
			(end -0.12065 0.2794)
			(stroke
				(width 0.1)
				(type default)
			)
			(layer "F.Fab")
		)
		(fp_line
			(start 0.120396 0.3048)
			(end 0.120396 0.2794)
			(stroke
				(width 0.1)
				(type default)
			)
			(layer "F.Fab")
		)
		(fp_line
			(start 0.12065 -0.3048)
			(end 0.67945 -0.3048)
			(stroke
				(width 0.1)
				(type default)
			)
			(layer "F.Fab")
		)
		(fp_line
			(start 0.12065 -0.2794)
			(end 0.12065 -0.3048)
			(stroke
				(width 0.1)
				(type default)
			)
			(layer "F.Fab")
		)
		(fp_line
			(start 0.67945 -0.3048)
			(end 0.67945 0.3048)
			(stroke
				(width 0.1)
				(type default)
			)
			(layer "F.Fab")
		)
		(fp_line
			(start 0.67945 0.3048)
			(end 0.120396 0.3048)
			(stroke
				(width 0.1)
				(type default)
			)
			(layer "F.Fab")
		)
		(pad "1" smd circle
			(at -0.40005 0)
			(size 0 0)
			(layers "F.Cu" "F.Mask" "F.Paste")
			(net "PVDDCR_CPU1_P1_LSET1")
		)
		(pad "2" smd circle
			(at 0.40005 0)
			(size 0 0)
			(layers "F.Cu" "F.Mask" "F.Paste")
			(net "GND")
		)
	)
	(footprint ""
		(layer "F.Cu")
		(at 182.5625 -397.848582 180)
		(property "Reference" "PC2190"
			(at 0 0 180)
			(layer "F.SilkS")
			(hide yes)
			(effects
				(font
					(size 1.27 1.27)
				)
			)
		)
		(property "Value" ""
			(at 0 0 180)
			(layer "F.Fab")
			(effects
				(font
					(size 1.27 1.27)
				)
			)
		)
		(duplicate_pad_numbers_are_jumpers no)
		(fp_line
			(start 0.7874 0.4064)
			(end -0.7874 0.4064)
			(stroke
				(width 0.1524)
				(type default)
			)
			(layer "F.SilkS")
		)
		(fp_line
			(start 0.7874 -0.4064)
			(end 0.7874 0.4064)
			(stroke
				(width 0.1524)
				(type default)
			)
			(layer "F.SilkS")
		)
		(fp_line
			(start -0.7874 0.4064)
			(end -0.7874 -0.4064)
			(stroke
				(width 0.1524)
				(type default)
			)
			(layer "F.SilkS")
		)
		(fp_line
			(start -0.7874 -0.4064)
			(end 0.7874 -0.4064)
			(stroke
				(width 0.1524)
				(type default)
			)
			(layer "F.SilkS")
		)
		(fp_line
			(start 0.67945 0.3048)
			(end 0.120396 0.3048)
			(stroke
				(width 0.1)
				(type default)
			)
			(layer "F.Fab")
		)
		(fp_line
			(start 0.67945 -0.3048)
			(end 0.67945 0.3048)
			(stroke
				(width 0.1)
				(type default)
			)
			(layer "F.Fab")
		)
		(fp_line
			(start 0.12065 -0.2794)
			(end 0.12065 -0.3048)
			(stroke
				(width 0.1)
				(type default)
			)
			(layer "F.Fab")
		)
		(fp_line
			(start 0.12065 -0.3048)
			(end 0.67945 -0.3048)
			(stroke
				(width 0.1)
				(type default)
			)
			(layer "F.Fab")
		)
		(fp_line
			(start 0.120396 0.3048)
			(end 0.120396 0.2794)
			(stroke
				(width 0.1)
				(type default)
			)
			(layer "F.Fab")
		)
		(fp_line
			(start 0.120396 0.2794)
			(end -0.12065 0.2794)
			(stroke
				(width 0.1)
				(type default)
			)
			(layer "F.Fab")
		)
		(fp_line
			(start -0.12065 0.3048)
			(end -0.67945 0.3048)
			(stroke
				(width 0.1)
				(type default)
			)
			(layer "F.Fab")
		)
		(fp_line
			(start -0.12065 0.2794)
			(end -0.12065 0.3048)
			(stroke
				(width 0.1)
				(type default)
			)
			(layer "F.Fab")
		)
		(fp_line
			(start -0.12065 -0.2794)
			(end 0.12065 -0.2794)
			(stroke
				(width 0.1)
				(type default)
			)
			(layer "F.Fab")
		)
		(fp_line
			(start -0.12065 -0.305054)
			(end -0.12065 -0.2794)
			(stroke
				(width 0.1)
				(type default)
			)
			(layer "F.Fab")
		)
		(fp_line
			(start -0.67945 0.3048)
			(end -0.67945 -0.305054)
			(stroke
				(width 0.1)
				(type default)
			)
			(layer "F.Fab")
		)
		(fp_line
			(start -0.67945 -0.305054)
			(end -0.12065 -0.305054)
			(stroke
				(width 0.1)
				(type default)
			)
			(layer "F.Fab")
		)
		(pad "1" smd circle
			(at -0.40005 0 180)
			(size 0 0)
			(layers "F.Cu" "F.Mask" "F.Paste")
			(net "HSC_VOSEN")
		)
		(pad "2" smd circle
			(at 0.40005 0 180)
			(size 0 0)
			(layers "F.Cu" "F.Mask" "F.Paste")
			(net "AGND_HSC")
		)
	)
	(footprint ""
		(layer "F.Cu")
		(at 80.622902 -375.49963 -90)
		(property "Reference" "C733"
			(at 0 0 270)
			(layer "F.SilkS")
			(hide yes)
			(effects
				(font
					(size 1.27 1.27)
				)
			)
		)
		(property "Value" ""
			(at 0 0 270)
			(layer "F.Fab")
			(effects
				(font
					(size 1.27 1.27)
				)
			)
		)
		(duplicate_pad_numbers_are_jumpers no)
		(fp_line
			(start -0.299974 0.150114)
			(end -0.299974 -0.150114)
			(stroke
				(width 0.1)
				(type default)
			)
			(layer "F.Fab")
		)
		(fp_line
			(start 0.299974 0.150114)
			(end -0.299974 0.150114)
			(stroke
				(width 0.1)
				(type default)
			)
			(layer "F.Fab")
		)
		(fp_line
			(start -0.299974 -0.150114)
			(end 0.299974 -0.150114)
			(stroke
				(width 0.1)
				(type default)
			)
			(layer "F.Fab")
		)
		(fp_line
			(start 0.299974 -0.150114)
			(end 0.299974 0.150114)
			(stroke
				(width 0.1)
				(type default)
			)
			(layer "F.Fab")
		)
		(pad "1" smd rect
			(at -0.2667 0 270)
			(size 0.3048 0.381)
			(layers "F.Cu" "F.Mask" "F.Paste")
			(net "P5E_CPU1_P1_TX_C_DP<4>")
		)
		(pad "2" smd rect
			(at 0.2667 0 270)
			(size 0.3048 0.381)
			(layers "F.Cu" "F.Mask" "F.Paste")
			(net "P5E_CPU1_P1_TX_DP<4>")
		)
	)
	(footprint ""
		(layer "F.Cu")
		(at 128.036066 -408.517344 -90)
		(property "Reference" "C6701"
			(at 0 0 270)
			(layer "F.SilkS")
			(hide yes)
			(effects
				(font
					(size 1.27 1.27)
				)
			)
		)
		(property "Value" ""
			(at 0 0 270)
			(layer "F.Fab")
			(effects
				(font
					(size 1.27 1.27)
				)
			)
		)
		(duplicate_pad_numbers_are_jumpers no)
		(fp_line
			(start -0.299974 0.150114)
			(end -0.299974 -0.150114)
			(stroke
				(width 0.1)
				(type default)
			)
			(layer "F.Fab")
		)
		(fp_line
			(start 0.299974 0.150114)
			(end -0.299974 0.150114)
			(stroke
				(width 0.1)
				(type default)
			)
			(layer "F.Fab")
		)
		(fp_line
			(start -0.299974 -0.150114)
			(end 0.299974 -0.150114)
			(stroke
				(width 0.1)
				(type default)
			)
			(layer "F.Fab")
		)
		(fp_line
			(start 0.299974 -0.150114)
			(end 0.299974 0.150114)
			(stroke
				(width 0.1)
				(type default)
			)
			(layer "F.Fab")
		)
		(pad "1" smd rect
			(at -0.2667 0 270)
			(size 0.3048 0.381)
			(layers "F.Cu" "F.Mask" "F.Paste")
			(net "P5E_CPU1_P2_TX_BUF_C_DP<4>")
		)
		(pad "2" smd rect
			(at 0.2667 0 270)
			(size 0.3048 0.381)
			(layers "F.Cu" "F.Mask" "F.Paste")
			(net "P5E_CPU1_P2_TX_BUF_DP<4>")
		)
	)
	(footprint ""
		(layer "F.Cu")
		(at 343.458546 -23.8887 -90)
		(property "Reference" "R945"
			(at 0 0 270)
			(layer "F.SilkS")
			(hide yes)
			(effects
				(font
					(size 1.27 1.27)
				)
			)
		)
		(property "Value" ""
			(at 0 0 270)
			(layer "F.Fab")
			(effects
				(font
					(size 1.27 1.27)
				)
			)
		)
		(duplicate_pad_numbers_are_jumpers no)
		(fp_line
			(start -0.7874 0.4064)
			(end -0.7874 -0.4064)
			(stroke
				(width 0.1524)
				(type default)
			)
			(layer "F.SilkS")
		)
		(fp_line
			(start 0.7874 0.4064)
			(end -0.7874 0.4064)
			(stroke
				(width 0.1524)
				(type default)
			)
			(layer "F.SilkS")
		)
		(fp_line
			(start -0.7874 -0.4064)
			(end 0.7874 -0.4064)
			(stroke
				(width 0.1524)
				(type default)
			)
			(layer "F.SilkS")
		)
		(fp_line
			(start 0.7874 -0.4064)
			(end 0.7874 0.4064)
			(stroke
				(width 0.1524)
				(type default)
			)
			(layer "F.SilkS")
		)
		(fp_line
			(start -0.67945 0.3048)
			(end -0.67945 -0.305054)
			(stroke
				(width 0.1)
				(type default)
			)
			(layer "F.Fab")
		)
		(fp_line
			(start -0.12065 0.3048)
			(end -0.67945 0.3048)
			(stroke
				(width 0.1)
				(type default)
			)
			(layer "F.Fab")
		)
		(fp_line
			(start 0.120396 0.3048)
			(end 0.120396 0.2794)
			(stroke
				(width 0.1)
				(type default)
			)
			(layer "F.Fab")
		)
		(fp_line
			(start 0.67945 0.3048)
			(end 0.120396 0.3048)
			(stroke
				(width 0.1)
				(type default)
			)
			(layer "F.Fab")
		)
		(fp_line
			(start -0.12065 0.2794)
			(end -0.12065 0.3048)
			(stroke
				(width 0.1)
				(type default)
			)
			(layer "F.Fab")
		)
		(fp_line
			(start 0.120396 0.2794)
			(end -0.12065 0.2794)
			(stroke
				(width 0.1)
				(type default)
			)
			(layer "F.Fab")
		)
		(fp_line
			(start -0.12065 -0.2794)
			(end 0.12065 -0.2794)
			(stroke
				(width 0.1)
				(type default)
			)
			(layer "F.Fab")
		)
		(fp_line
			(start 0.12065 -0.2794)
			(end 0.12065 -0.3048)
			(stroke
				(width 0.1)
				(type default)
			)
			(layer "F.Fab")
		)
		(fp_line
			(start 0.12065 -0.3048)
			(end 0.67945 -0.3048)
			(stroke
				(width 0.1)
				(type default)
			)
			(layer "F.Fab")
		)
		(fp_line
			(start 0.67945 -0.3048)
			(end 0.67945 0.3048)
			(stroke
				(width 0.1)
				(type default)
			)
			(layer "F.Fab")
		)
		(fp_line
			(start -0.67945 -0.305054)
			(end -0.12065 -0.305054)
			(stroke
				(width 0.1)
				(type default)
			)
			(layer "F.Fab")
		)
		(fp_line
			(start -0.12065 -0.305054)
			(end -0.12065 -0.2794)
			(stroke
				(width 0.1)
				(type default)
			)
			(layer "F.Fab")
		)
		(pad "1" smd circle
			(at -0.40005 0 270)
			(size 0 0)
			(layers "F.Cu" "F.Mask" "F.Paste")
			(net "P3V3_AUX")
		)
		(pad "2" smd circle
			(at 0.40005 0 270)
			(size 0 0)
			(layers "F.Cu" "F.Mask" "F.Paste")
			(net "FM_SMERR_BUF_R_LED_N")
		)
	)
)
